(kicad_pcb
	(version 20260206)
	(generator "pcbnew")
	(generator_version "10.0")
	(general
		(thickness 1.6)
		(legacy_teardrops no)
	)
	(paper "A4")
	(title_block
		(title "04192023_DAF0TMB3IC0_F0TG_MB_C_brd_V02_OCP.brd")
		(comment 1 "Grand Teton / footprints 5531-5538 of 8354")
	)
	(layers
		(0 "F.Cu" signal "TOP")
		(4 "In1.Cu" signal "GND")
		(6 "In2.Cu" signal "IN1")
		(8 "In3.Cu" signal "GND1")
		(10 "In4.Cu" signal "IN2")
		(12 "In5.Cu" signal "GND2")
		(14 "In6.Cu" signal "IN3")
		(16 "In7.Cu" signal "GND3")
		(18 "In8.Cu" signal "VCC")
		(20 "In9.Cu" signal "VCC1")
		(22 "In10.Cu" signal "GND4")
		(24 "In11.Cu" signal "IN4")
		(26 "In12.Cu" signal "GND5")
		(28 "In13.Cu" signal "IN5")
		(30 "In14.Cu" signal "GND6")
		(32 "In15.Cu" signal "IN6")
		(34 "In16.Cu" signal "GND7")
		(2 "B.Cu" signal "BOTTOM")
		(9 "F.Adhes" user "F.Adhesive")
		(11 "B.Adhes" user "B.Adhesive")
		(13 "F.Paste" user "Package Geometry/Pastemask Top")
		(15 "B.Paste" user "Package Geometry/Pastemask Bottom")
		(5 "F.SilkS" user "Ref Des/Silkscreen Top")
		(7 "B.SilkS" user "Ref Des/Silkscreen Bottom")
		(1 "F.Mask" user "Board Geometry/Soldermask Top")
		(3 "B.Mask" user "Board Geometry/Soldermask Bottom")
		(17 "Dwgs.User" user "User.Drawings")
		(19 "Cmts.User" user "User.Comments")
		(21 "Eco1.User" user "User.Eco1")
		(23 "Eco2.User" user "User.Eco2")
		(25 "Edge.Cuts" user "Board Geometry/Outline")
		(27 "Margin" user)
		(31 "F.CrtYd" user "Package Geometry/Place Bound Top")
		(29 "B.CrtYd" user "Package Geometry/Place Bound Bottom")
		(35 "F.Fab" user "Ref Des/Assembly Top")
		(33 "B.Fab" user "Ref Des/Assembly Bottom")
	)
	(footprint ""
		(layer "B.Cu")
		(at 116.116354 -178.658012 90)
		(property "Reference" "PC343"
			(at 6.671056 -0.439166 270)
			(unlocked yes)
			(layer "B.SilkS")
			(effects
				(font
					(size 0.7874 0.5842)
					(thickness 0.1524)
				)
				(justify left mirror)
			)
		)
		(property "Value" ""
			(at 0 0 90)
			(layer "B.Fab")
			(effects
				(font
					(size 1.27 1.27)
				)
				(justify mirror)
			)
		)
		(duplicate_pad_numbers_are_jumpers no)
		(fp_line
			(start 4.533392 -2.249932)
			(end -4.533392 -2.249932)
			(stroke
				(width 0.1524)
				(type default)
			)
			(layer "B.SilkS")
		)
		(fp_line
			(start -4.533392 -2.249932)
			(end -4.533392 2.249932)
			(stroke
				(width 0.1524)
				(type default)
			)
			(layer "B.SilkS")
		)
		(fp_line
			(start 4.533392 2.249932)
			(end 4.533392 -2.249932)
			(stroke
				(width 0.1524)
				(type default)
			)
			(layer "B.SilkS")
		)
		(fp_line
			(start -4.533392 2.249932)
			(end 4.533392 2.249932)
			(stroke
				(width 0.1524)
				(type default)
			)
			(layer "B.SilkS")
		)
		(fp_rect
			(start 4.533392 -2.326132)
			(end 5.39242 2.326132)
			(stroke
				(width 0)
				(type default)
			)
			(fill yes)
			(layer "B.SilkS")
		)
		(fp_line
			(start 3.750056 -2.249932)
			(end -3.750056 -2.249932)
			(stroke
				(width 0.1)
				(type default)
			)
			(layer "B.Fab")
		)
		(fp_line
			(start -3.750056 -2.249932)
			(end -3.750056 2.249932)
			(stroke
				(width 0.1)
				(type default)
			)
			(layer "B.Fab")
		)
		(fp_line
			(start 3.750056 2.249932)
			(end 3.750056 -2.249932)
			(stroke
				(width 0.1)
				(type default)
			)
			(layer "B.Fab")
		)
		(fp_line
			(start -3.750056 2.249932)
			(end 3.750056 2.249932)
			(stroke
				(width 0.1)
				(type default)
			)
			(layer "B.Fab")
		)
		(fp_text user "-"
			(at -4.8514 -0.14605 90)
			(unlocked yes)
			(layer "B.SilkS")
			(effects
				(font
					(size 1.905 1.4224)
					(thickness 0.1524)
				)
				(justify left mirror)
			)
		)
		(fp_text user "+"
			(at 6.322314 0.786384 0)
			(unlocked yes)
			(layer "B.SilkS")
			(effects
				(font
					(size 1.905 1.4224)
					(thickness 0.1524)
				)
				(justify left mirror)
			)
		)
		(fp_text user "-"
			(at -4.8514 -0.14605 90)
			(unlocked yes)
			(layer "B.Fab")
			(effects
				(font
					(size 1.905 1.4224)
					(thickness 0.1524)
				)
				(justify left mirror)
			)
		)
		(fp_text user "+"
			(at 6.322314 0.786384 0)
			(unlocked yes)
			(layer "B.Fab")
			(effects
				(font
					(size 1.905 1.4224)
					(thickness 0.1524)
				)
				(justify left mirror)
			)
		)
		(pad "1" smd rect
			(at 3.199892 0 270)
			(size 2.413 2.8194)
			(layers "B.Cu" "B.Mask" "B.Paste")
			(net "PVDDCR_SOC_P1")
		)
		(pad "2" smd rect
			(at -3.199892 0 270)
			(size 2.413 2.8194)
			(layers "B.Cu" "B.Mask" "B.Paste")
			(net "GND")
		)
	)
	(footprint ""
		(layer "B.Cu")
		(at 357.517192 -261.747762 90)
		(property "Reference" "C2153"
			(at 0 0 90)
			(layer "B.SilkS")
			(hide yes)
			(effects
				(font
					(size 1.27 1.27)
				)
				(justify mirror)
			)
		)
		(property "Value" ""
			(at 0 0 90)
			(layer "B.Fab")
			(effects
				(font
					(size 1.27 1.27)
				)
				(justify mirror)
			)
		)
		(duplicate_pad_numbers_are_jumpers no)
		(fp_line
			(start 0.7874 -0.4064)
			(end -0.7874 -0.4064)
			(stroke
				(width 0.1524)
				(type default)
			)
			(layer "B.SilkS")
		)
		(fp_line
			(start -0.7874 -0.4064)
			(end -0.7874 0.4064)
			(stroke
				(width 0.1524)
				(type default)
			)
			(layer "B.SilkS")
		)
		(fp_line
			(start 0.7874 0.4064)
			(end 0.7874 -0.4064)
			(stroke
				(width 0.1524)
				(type default)
			)
			(layer "B.SilkS")
		)
		(fp_line
			(start -0.7874 0.4064)
			(end 0.7874 0.4064)
			(stroke
				(width 0.1524)
				(type default)
			)
			(layer "B.SilkS")
		)
		(fp_line
			(start 0.67945 -0.305054)
			(end 0.12065 -0.305054)
			(stroke
				(width 0.1)
				(type default)
			)
			(layer "B.Fab")
		)
		(fp_line
			(start 0.12065 -0.305054)
			(end 0.12065 -0.2794)
			(stroke
				(width 0.1)
				(type default)
			)
			(layer "B.Fab")
		)
		(fp_line
			(start -0.12065 -0.3048)
			(end -0.67945 -0.3048)
			(stroke
				(width 0.1)
				(type default)
			)
			(layer "B.Fab")
		)
		(fp_line
			(start -0.67945 -0.3048)
			(end -0.67945 0.3048)
			(stroke
				(width 0.1)
				(type default)
			)
			(layer "B.Fab")
		)
		(fp_line
			(start 0.12065 -0.2794)
			(end -0.12065 -0.2794)
			(stroke
				(width 0.1)
				(type default)
			)
			(layer "B.Fab")
		)
		(fp_line
			(start -0.12065 -0.2794)
			(end -0.12065 -0.3048)
			(stroke
				(width 0.1)
				(type default)
			)
			(layer "B.Fab")
		)
		(fp_line
			(start 0.12065 0.2794)
			(end 0.12065 0.3048)
			(stroke
				(width 0.1)
				(type default)
			)
			(layer "B.Fab")
		)
		(fp_line
			(start -0.120396 0.2794)
			(end 0.12065 0.2794)
			(stroke
				(width 0.1)
				(type default)
			)
			(layer "B.Fab")
		)
		(fp_line
			(start 0.67945 0.3048)
			(end 0.67945 -0.305054)
			(stroke
				(width 0.1)
				(type default)
			)
			(layer "B.Fab")
		)
		(fp_line
			(start 0.12065 0.3048)
			(end 0.67945 0.3048)
			(stroke
				(width 0.1)
				(type default)
			)
			(layer "B.Fab")
		)
		(fp_line
			(start -0.120396 0.3048)
			(end -0.120396 0.2794)
			(stroke
				(width 0.1)
				(type default)
			)
			(layer "B.Fab")
		)
		(fp_line
			(start -0.67945 0.3048)
			(end -0.120396 0.3048)
			(stroke
				(width 0.1)
				(type default)
			)
			(layer "B.Fab")
		)
		(pad "1" smd circle
			(at 0.40005 0 270)
			(size 0 0)
			(layers "B.Cu" "B.Mask" "B.Paste")
			(net "PVDD11_S3_P0")
		)
		(pad "2" smd circle
			(at -0.40005 0 270)
			(size 0 0)
			(layers "B.Cu" "B.Mask" "B.Paste")
			(net "GND")
		)
	)
	(footprint ""
		(layer "B.Cu")
		(at 126.892304 -32.867092 -90)
		(property "Reference" "C6075"
			(at 0 0 90)
			(layer "B.SilkS")
			(hide yes)
			(effects
				(font
					(size 1.27 1.27)
				)
				(justify mirror)
			)
		)
		(property "Value" ""
			(at 0 0 90)
			(layer "B.Fab")
			(effects
				(font
					(size 1.27 1.27)
				)
				(justify mirror)
			)
		)
		(duplicate_pad_numbers_are_jumpers no)
		(fp_line
			(start -0.7874 0.4064)
			(end 0.7874 0.4064)
			(stroke
				(width 0.1524)
				(type default)
			)
			(layer "B.SilkS")
		)
		(fp_line
			(start 0.7874 0.4064)
			(end 0.7874 -0.4064)
			(stroke
				(width 0.1524)
				(type default)
			)
			(layer "B.SilkS")
		)
		(fp_line
			(start -0.7874 -0.4064)
			(end -0.7874 0.4064)
			(stroke
				(width 0.1524)
				(type default)
			)
			(layer "B.SilkS")
		)
		(fp_line
			(start 0.7874 -0.4064)
			(end -0.7874 -0.4064)
			(stroke
				(width 0.1524)
				(type default)
			)
			(layer "B.SilkS")
		)
		(fp_line
			(start -0.67945 0.3048)
			(end -0.120396 0.3048)
			(stroke
				(width 0.1)
				(type default)
			)
			(layer "B.Fab")
		)
		(fp_line
			(start -0.120396 0.3048)
			(end -0.120396 0.2794)
			(stroke
				(width 0.1)
				(type default)
			)
			(layer "B.Fab")
		)
		(fp_line
			(start 0.12065 0.3048)
			(end 0.67945 0.3048)
			(stroke
				(width 0.1)
				(type default)
			)
			(layer "B.Fab")
		)
		(fp_line
			(start 0.67945 0.3048)
			(end 0.67945 -0.305054)
			(stroke
				(width 0.1)
				(type default)
			)
			(layer "B.Fab")
		)
		(fp_line
			(start -0.120396 0.2794)
			(end 0.12065 0.2794)
			(stroke
				(width 0.1)
				(type default)
			)
			(layer "B.Fab")
		)
		(fp_line
			(start 0.12065 0.2794)
			(end 0.12065 0.3048)
			(stroke
				(width 0.1)
				(type default)
			)
			(layer "B.Fab")
		)
		(fp_line
			(start -0.12065 -0.2794)
			(end -0.12065 -0.3048)
			(stroke
				(width 0.1)
				(type default)
			)
			(layer "B.Fab")
		)
		(fp_line
			(start 0.12065 -0.2794)
			(end -0.12065 -0.2794)
			(stroke
				(width 0.1)
				(type default)
			)
			(layer "B.Fab")
		)
		(fp_line
			(start -0.67945 -0.3048)
			(end -0.67945 0.3048)
			(stroke
				(width 0.1)
				(type default)
			)
			(layer "B.Fab")
		)
		(fp_line
			(start -0.12065 -0.3048)
			(end -0.67945 -0.3048)
			(stroke
				(width 0.1)
				(type default)
			)
			(layer "B.Fab")
		)
		(fp_line
			(start 0.12065 -0.305054)
			(end 0.12065 -0.2794)
			(stroke
				(width 0.1)
				(type default)
			)
			(layer "B.Fab")
		)
		(fp_line
			(start 0.67945 -0.305054)
			(end 0.12065 -0.305054)
			(stroke
				(width 0.1)
				(type default)
			)
			(layer "B.Fab")
		)
		(pad "1" smd circle
			(at 0.40005 0 90)
			(size 0 0)
			(layers "B.Cu" "B.Mask" "B.Paste")
			(net "P1V2_AUX")
		)
		(pad "2" smd circle
			(at -0.40005 0 90)
			(size 0 0)
			(layers "B.Cu" "B.Mask" "B.Paste")
			(net "GND")
		)
	)
	(footprint ""
		(layer "B.Cu")
		(at 255.905 -340.76132 180)
		(property "Reference" "R799"
			(at 0 0 0)
			(layer "B.SilkS")
			(hide yes)
			(effects
				(font
					(size 1.27 1.27)
				)
				(justify mirror)
			)
		)
		(property "Value" ""
			(at 0 0 0)
			(layer "B.Fab")
			(effects
				(font
					(size 1.27 1.27)
				)
				(justify mirror)
			)
		)
		(duplicate_pad_numbers_are_jumpers no)
		(fp_line
			(start 0.32512 0.175006)
			(end 0.32512 -0.175006)
			(stroke
				(width 0.1)
				(type default)
			)
			(layer "B.Fab")
		)
		(fp_line
			(start 0.32512 -0.175006)
			(end -0.32512 -0.175006)
			(stroke
				(width 0.1)
				(type default)
			)
			(layer "B.Fab")
		)
		(fp_line
			(start -0.32512 0.175006)
			(end 0.32512 0.175006)
			(stroke
				(width 0.1)
				(type default)
			)
			(layer "B.Fab")
		)
		(fp_line
			(start -0.32512 -0.175006)
			(end -0.32512 0.175006)
			(stroke
				(width 0.1)
				(type default)
			)
			(layer "B.Fab")
		)
		(pad "1" smd rect
			(at 0.2667 0)
			(size 0.3048 0.381)
			(layers "B.Cu" "B.Mask" "B.Paste")
			(net "SMB_RT_CPU0_P0_ROM_MUX_2D_R_SCL")
		)
		(pad "2" smd rect
			(at -0.2667 0 180)
			(size 0.3048 0.381)
			(layers "B.Cu" "B.Mask" "B.Paste")
			(net "SMB_RT_CPU0_P0_ROM_MUX_2D_SCL")
		)
	)
	(footprint ""
		(layer "B.Cu")
		(at 157.226 -416.9664 180)
		(property "Reference" "R1468"
			(at 0 0 0)
			(layer "B.SilkS")
			(hide yes)
			(effects
				(font
					(size 1.27 1.27)
				)
				(justify mirror)
			)
		)
		(property "Value" ""
			(at 0 0 0)
			(layer "B.Fab")
			(effects
				(font
					(size 1.27 1.27)
				)
				(justify mirror)
			)
		)
		(duplicate_pad_numbers_are_jumpers no)
		(fp_line
			(start 0.32512 0.175006)
			(end 0.32512 -0.175006)
			(stroke
				(width 0.1)
				(type default)
			)
			(layer "B.Fab")
		)
		(fp_line
			(start 0.32512 -0.175006)
			(end -0.32512 -0.175006)
			(stroke
				(width 0.1)
				(type default)
			)
			(layer "B.Fab")
		)
		(fp_line
			(start -0.32512 0.175006)
			(end 0.32512 0.175006)
			(stroke
				(width 0.1)
				(type default)
			)
			(layer "B.Fab")
		)
		(fp_line
			(start -0.32512 -0.175006)
			(end -0.32512 0.175006)
			(stroke
				(width 0.1)
				(type default)
			)
			(layer "B.Fab")
		)
		(pad "1" smd rect
			(at 0.2667 0)
			(size 0.3048 0.381)
			(layers "B.Cu" "B.Mask" "B.Paste")
			(net "P1V8_CPU1_RT_1D")
		)
		(pad "2" smd rect
			(at -0.2667 0 180)
			(size 0.3048 0.381)
			(layers "B.Cu" "B.Mask" "B.Paste")
			(net "SMB_RT_CPU1_P2_ROM_MUX_1D_SDA")
		)
	)
	(footprint ""
		(layer "B.Cu")
		(at 16.367252 -421.594026 -90)
		(property "Reference" "C1865"
			(at 0 0 90)
			(layer "B.SilkS")
			(hide yes)
			(effects
				(font
					(size 1.27 1.27)
				)
				(justify mirror)
			)
		)
		(property "Value" ""
			(at 0 0 90)
			(layer "B.Fab")
			(effects
				(font
					(size 1.27 1.27)
				)
				(justify mirror)
			)
		)
		(duplicate_pad_numbers_are_jumpers no)
		(fp_line
			(start -0.7874 0.4064)
			(end 0.7874 0.4064)
			(stroke
				(width 0.1524)
				(type default)
			)
			(layer "B.SilkS")
		)
		(fp_line
			(start 0.7874 0.4064)
			(end 0.7874 -0.4064)
			(stroke
				(width 0.1524)
				(type default)
			)
			(layer "B.SilkS")
		)
		(fp_line
			(start -0.7874 -0.4064)
			(end -0.7874 0.4064)
			(stroke
				(width 0.1524)
				(type default)
			)
			(layer "B.SilkS")
		)
		(fp_line
			(start 0.7874 -0.4064)
			(end -0.7874 -0.4064)
			(stroke
				(width 0.1524)
				(type default)
			)
			(layer "B.SilkS")
		)
		(fp_line
			(start -0.67945 0.3048)
			(end -0.120396 0.3048)
			(stroke
				(width 0.1)
				(type default)
			)
			(layer "B.Fab")
		)
		(fp_line
			(start -0.120396 0.3048)
			(end -0.120396 0.2794)
			(stroke
				(width 0.1)
				(type default)
			)
			(layer "B.Fab")
		)
		(fp_line
			(start 0.12065 0.3048)
			(end 0.67945 0.3048)
			(stroke
				(width 0.1)
				(type default)
			)
			(layer "B.Fab")
		)
		(fp_line
			(start 0.67945 0.3048)
			(end 0.67945 -0.305054)
			(stroke
				(width 0.1)
				(type default)
			)
			(layer "B.Fab")
		)
		(fp_line
			(start -0.120396 0.2794)
			(end 0.12065 0.2794)
			(stroke
				(width 0.1)
				(type default)
			)
			(layer "B.Fab")
		)
		(fp_line
			(start 0.12065 0.2794)
			(end 0.12065 0.3048)
			(stroke
				(width 0.1)
				(type default)
			)
			(layer "B.Fab")
		)
		(fp_line
			(start -0.12065 -0.2794)
			(end -0.12065 -0.3048)
			(stroke
				(width 0.1)
				(type default)
			)
			(layer "B.Fab")
		)
		(fp_line
			(start 0.12065 -0.2794)
			(end -0.12065 -0.2794)
			(stroke
				(width 0.1)
				(type default)
			)
			(layer "B.Fab")
		)
		(fp_line
			(start -0.67945 -0.3048)
			(end -0.67945 0.3048)
			(stroke
				(width 0.1)
				(type default)
			)
			(layer "B.Fab")
		)
		(fp_line
			(start -0.12065 -0.3048)
			(end -0.67945 -0.3048)
			(stroke
				(width 0.1)
				(type default)
			)
			(layer "B.Fab")
		)
		(fp_line
			(start 0.12065 -0.305054)
			(end 0.12065 -0.2794)
			(stroke
				(width 0.1)
				(type default)
			)
			(layer "B.Fab")
		)
		(fp_line
			(start 0.67945 -0.305054)
			(end 0.12065 -0.305054)
			(stroke
				(width 0.1)
				(type default)
			)
			(layer "B.Fab")
		)
		(pad "1" smd circle
			(at 0.40005 0 90)
			(size 0 0)
			(layers "B.Cu" "B.Mask" "B.Paste")
			(net "P3V3_AUX")
		)
		(pad "2" smd circle
			(at -0.40005 0 90)
			(size 0 0)
			(layers "B.Cu" "B.Mask" "B.Paste")
			(net "GND")
		)
	)
	(footprint ""
		(layer "B.Cu")
		(at 455.111104 -65.768982 90)
		(property "Reference" "PC1599"
			(at 0 0 90)
			(layer "B.SilkS")
			(hide yes)
			(effects
				(font
					(size 1.27 1.27)
				)
				(justify mirror)
			)
		)
		(property "Value" ""
			(at 0 0 90)
			(layer "B.Fab")
			(effects
				(font
					(size 1.27 1.27)
				)
				(justify mirror)
			)
		)
		(duplicate_pad_numbers_are_jumpers no)
		(fp_line
			(start 1.524 -0.762)
			(end -1.524 -0.762)
			(stroke
				(width 0.1524)
				(type default)
			)
			(layer "B.SilkS")
		)
		(fp_line
			(start -1.524 -0.762)
			(end -1.524 0.762)
			(stroke
				(width 0.1524)
				(type default)
			)
			(layer "B.SilkS")
		)
		(fp_line
			(start 1.524 0.762)
			(end 1.524 -0.762)
			(stroke
				(width 0.1524)
				(type default)
			)
			(layer "B.SilkS")
		)
		(fp_line
			(start -1.524 0.762)
			(end 1.524 0.762)
			(stroke
				(width 0.1524)
				(type default)
			)
			(layer "B.SilkS")
		)
		(fp_line
			(start 1.1049 -0.724916)
			(end 1.1049 0.724916)
			(stroke
				(width 0.1)
				(type default)
			)
			(layer "B.Fab")
		)
		(fp_line
			(start -1.1049 -0.724916)
			(end 1.1049 -0.724916)
			(stroke
				(width 0.1)
				(type default)
			)
			(layer "B.Fab")
		)
		(fp_line
			(start 1.1049 0.724916)
			(end -1.1049 0.724916)
			(stroke
				(width 0.1)
				(type default)
			)
			(layer "B.Fab")
		)
		(fp_line
			(start -1.1049 0.724916)
			(end -1.1049 -0.724916)
			(stroke
				(width 0.1)
				(type default)
			)
			(layer "B.Fab")
		)
		(pad "1" smd rect
			(at 0.889 0 90)
			(size 1.016 1.27)
			(layers "B.Cu" "B.Mask" "B.Paste")
			(net "P3V3_AUX")
		)
		(pad "2" smd rect
			(at -0.889 0 90)
			(size 1.016 1.27)
			(layers "B.Cu" "B.Mask" "B.Paste")
			(net "GND")
		)
	)
	(footprint ""
		(layer "B.Cu")
		(at 449.910454 -191.32931 180)
		(property "Reference" "R302"
			(at 0 0 0)
			(layer "B.SilkS")
			(hide yes)
			(effects
				(font
					(size 1.27 1.27)
				)
				(justify mirror)
			)
		)
		(property "Value" ""
			(at 0 0 0)
			(layer "B.Fab")
			(effects
				(font
					(size 1.27 1.27)
				)
				(justify mirror)
			)
		)
		(duplicate_pad_numbers_are_jumpers no)
		(fp_line
			(start 0.7874 0.4064)
			(end 0.7874 -0.4064)
			(stroke
				(width 0.1524)
				(type default)
			)
			(layer "B.SilkS")
		)
		(fp_line
			(start 0.7874 -0.4064)
			(end -0.7874 -0.4064)
			(stroke
				(width 0.1524)
				(type default)
			)
			(layer "B.SilkS")
		)
		(fp_line
			(start -0.7874 0.4064)
			(end 0.7874 0.4064)
			(stroke
				(width 0.1524)
				(type default)
			)
			(layer "B.SilkS")
		)
		(fp_line
			(start -0.7874 -0.4064)
			(end -0.7874 0.4064)
			(stroke
				(width 0.1524)
				(type default)
			)
			(layer "B.SilkS")
		)
		(fp_line
			(start 0.67945 0.3048)
			(end 0.67945 -0.305054)
			(stroke
				(width 0.1)
				(type default)
			)
			(layer "B.Fab")
		)
		(fp_line
			(start 0.67945 -0.305054)
			(end 0.12065 -0.305054)
			(stroke
				(width 0.1)
				(type default)
			)
			(layer "B.Fab")
		)
		(fp_line
			(start 0.12065 0.3048)
			(end 0.67945 0.3048)
			(stroke
				(width 0.1)
				(type default)
			)
			(layer "B.Fab")
		)
		(fp_line
			(start 0.12065 0.2794)
			(end 0.12065 0.3048)
			(stroke
				(width 0.1)
				(type default)
			)
			(layer "B.Fab")
		)
		(fp_line
			(start 0.12065 -0.2794)
			(end -0.12065 -0.2794)
			(stroke
				(width 0.1)
				(type default)
			)
			(layer "B.Fab")
		)
		(fp_line
			(start 0.12065 -0.305054)
			(end 0.12065 -0.2794)
			(stroke
				(width 0.1)
				(type default)
			)
			(layer "B.Fab")
		)
		(fp_line
			(start -0.120396 0.3048)
			(end -0.120396 0.2794)
			(stroke
				(width 0.1)
				(type default)
			)
			(layer "B.Fab")
		)
		(fp_line
			(start -0.120396 0.2794)
			(end 0.12065 0.2794)
			(stroke
				(width 0.1)
				(type default)
			)
			(layer "B.Fab")
		)
		(fp_line
			(start -0.12065 -0.2794)
			(end -0.12065 -0.3048)
			(stroke
				(width 0.1)
				(type default)
			)
			(layer "B.Fab")
		)
		(fp_line
			(start -0.12065 -0.3048)
			(end -0.67945 -0.3048)
			(stroke
				(width 0.1)
				(type default)
			)
			(layer "B.Fab")
		)
		(fp_line
			(start -0.67945 0.3048)
			(end -0.120396 0.3048)
			(stroke
				(width 0.1)
				(type default)
			)
			(layer "B.Fab")
		)
		(fp_line
			(start -0.67945 -0.3048)
			(end -0.67945 0.3048)
			(stroke
				(width 0.1)
				(type default)
			)
			(layer "B.Fab")
		)
		(pad "1" smd circle
			(at 0.40005 0)
			(size 0 0)
			(layers "B.Cu" "B.Mask" "B.Paste")
			(net "PWRGD_CHL_CPU0_DIMM")
		)
		(pad "2" smd circle
			(at -0.40005 0)
			(size 0 0)
			(layers "B.Cu" "B.Mask" "B.Paste")
			(net "PWRGD_CHGL_CPU0")
		)
	)
)
